FILE_TYPE=LIBRARY_PARTS;
primitive 'RS31312R';
  pin
    'VOUT_20':
      PIN_NUMBER='(20)';
      OUTPUT_LOAD='(1.0,-1.0)';
    'VIN_21_22':
      PIN_NUMBER='(21_22)';
      INPUT_LOAD='(-0.01,0.01)';
    'VOUT_19':
      PIN_NUMBER='(19)';
      OUTPUT_LOAD='(1.0,-1.0)';
    'VOUT_18':
      PIN_NUMBER='(18)';
      OUTPUT_LOAD='(1.0,-1.0)';
    'VOUT_17':
      PIN_NUMBER='(17)';
      OUTPUT_LOAD='(1.0,-1.0)';
    'VOUT_16':
      PIN_NUMBER='(16)';
      OUTPUT_LOAD='(1.0,-1.0)';
    'VOUT_15':
      PIN_NUMBER='(15)';
      OUTPUT_LOAD='(1.0,-1.0)';
    'VOUT_14':
      PIN_NUMBER='(14)';
      OUTPUT_LOAD='(1.0,-1.0)';
    'AVIN':
      PIN_NUMBER='(12)';
      INPUT_LOAD='(-0.01,0.01)';
    'VOUT_13':
      PIN_NUMBER='(13)';
      OUTPUT_LOAD='(1.0,-1.0)';
    'OV':
      PIN_NUMBER='(11)';
      INPUT_LOAD='(-0.01,0.01)';
    'PG':
      PIN_NUMBER='(10)';
      OUTPUT_LOAD='(1.0,-1.0)';
    'FLTB':
      PIN_NUMBER='(9)';
      OUTPUT_LOAD='(1.0,-1.0)';
    'IMON':
      PIN_NUMBER='(8)';
      OUTPUT_LOAD='(1.0,-1.0)';
    'VIN_23':
      PIN_NUMBER='(23)';
      INPUT_LOAD='(-0.01,0.01)';
    'VIN_24':
      PIN_NUMBER='(24)';
      INPUT_LOAD='(-0.01,0.01)';
    'VIN_25':
      PIN_NUMBER='(25)';
      INPUT_LOAD='(-0.01,0.01)';
    'VIN_26':
      PIN_NUMBER='(26)';
      INPUT_LOAD='(-0.01,0.01)';
    'EN':
      PIN_NUMBER='(1)';
      INPUT_LOAD='(-0.01,0.01)';
    'LOADEN':
      PIN_NUMBER='(2)';
      INPUT_LOAD='(-0.01,0.01)';
    'ENTM':
      PIN_NUMBER='(3)';
      INPUT_LOAD='(-0.01,0.01)';
    'TIMER':
      PIN_NUMBER='(4)';
      INPUT_LOAD='(-0.01,0.01)';
    'ISET':
      PIN_NUMBER='(5)';
      INPUT_LOAD='(-0.01,0.01)';
    'SS':
      PIN_NUMBER='(6)';
      INPUT_LOAD='(-0.01,0.01)';
    'GND':
      PIN_NUMBER='(7)';
      PINUSE='POWER';
      NO_LOAD_CHECK='Both';
      NO_IO_CHECK='Both';
      NO_ASSERT_CHECK='TRUE';
      NO_DIR_CHECK='TRUE';
      ALLOW_CONNECT='TRUE';
  end_pin;
  body
    PART_NAME='RS31312R';
    BODY_NAME='RS31312R';
    PHYS_DES_PREFIX='U';
    CLASS='IC';
  end_body;
end_primitive;

END.
